(kicad_pcb
	(version 20260206)
	(generator "pcbnew")
	(generator_version "10.0")
	(general
		(thickness 1.6)
		(legacy_teardrops no)
	)
	(paper "A4")
	(title_block
		(title "03242023_DA0F0TMBIJ0_F0T_Motherboard_J_brd_V01_OCP.brd")
		(comment 1 "Grand Teton / footprints 169-174 of 6105")
	)
	(layers
		(0 "F.Cu" signal "TOP")
		(4 "In1.Cu" signal "GND")
		(6 "In2.Cu" signal "IN1")
		(8 "In3.Cu" signal "GND1")
		(10 "In4.Cu" signal "IN2")
		(12 "In5.Cu" signal "GND2")
		(14 "In6.Cu" signal "IN3")
		(16 "In7.Cu" signal "GND3")
		(18 "In8.Cu" signal "VCC")
		(20 "In9.Cu" signal "VCC1")
		(22 "In10.Cu" signal "GND4")
		(24 "In11.Cu" signal "IN4")
		(26 "In12.Cu" signal "GND5")
		(28 "In13.Cu" signal "IN5")
		(30 "In14.Cu" signal "GND6")
		(32 "In15.Cu" signal "IN6")
		(34 "In16.Cu" signal "GND7")
		(2 "B.Cu" signal "BOTTOM")
		(9 "F.Adhes" user "F.Adhesive")
		(11 "B.Adhes" user "B.Adhesive")
		(13 "F.Paste" user "Package Geometry/Pastemask Top")
		(15 "B.Paste" user "Package Geometry/Pastemask Bottom")
		(5 "F.SilkS" user "Ref Des/Silkscreen Top")
		(7 "B.SilkS" user "Ref Des/Silkscreen Bottom")
		(1 "F.Mask" user "Board Geometry/Soldermask Top")
		(3 "B.Mask" user "Board Geometry/Soldermask Bottom")
		(17 "Dwgs.User" user "User.Drawings")
		(19 "Cmts.User" user "User.Comments")
		(21 "Eco1.User" user "User.Eco1")
		(23 "Eco2.User" user "User.Eco2")
		(25 "Edge.Cuts" user "Board Geometry/Outline")
		(27 "Margin" user)
		(31 "F.CrtYd" user "Package Geometry/Place Bound Top")
		(29 "B.CrtYd" user "Package Geometry/Place Bound Bottom")
		(35 "F.Fab" user "Ref Des/Assembly Top")
		(33 "B.Fab" user "Ref Des/Assembly Bottom")
	)
	(footprint ""
		(layer "F.Cu")
		(at 218.12758 -130.957828)
		(property "Reference" "C1316"
			(at 0 0 0)
			(layer "F.SilkS")
			(hide yes)
			(effects
				(font
					(size 1.27 1.27)
				)
			)
		)
		(property "Value" ""
			(at 0 0 0)
			(layer "F.Fab")
			(effects
				(font
					(size 1.27 1.27)
				)
			)
		)
		(duplicate_pad_numbers_are_jumpers no)
		(fp_line
			(start -0.7874 -0.4064)
			(end 0.7874 -0.4064)
			(stroke
				(width 0.1524)
				(type default)
			)
			(layer "F.SilkS")
		)
		(fp_line
			(start -0.7874 0.4064)
			(end -0.7874 -0.4064)
			(stroke
				(width 0.1524)
				(type default)
			)
			(layer "F.SilkS")
		)
		(fp_line
			(start 0.7874 -0.4064)
			(end 0.7874 0.4064)
			(stroke
				(width 0.1524)
				(type default)
			)
			(layer "F.SilkS")
		)
		(fp_line
			(start 0.7874 0.4064)
			(end -0.7874 0.4064)
			(stroke
				(width 0.1524)
				(type default)
			)
			(layer "F.SilkS")
		)
		(fp_line
			(start -0.67945 -0.305054)
			(end -0.12065 -0.305054)
			(stroke
				(width 0.1)
				(type default)
			)
			(layer "F.Fab")
		)
		(fp_line
			(start -0.67945 0.3048)
			(end -0.67945 -0.305054)
			(stroke
				(width 0.1)
				(type default)
			)
			(layer "F.Fab")
		)
		(fp_line
			(start -0.12065 -0.305054)
			(end -0.12065 -0.2794)
			(stroke
				(width 0.1)
				(type default)
			)
			(layer "F.Fab")
		)
		(fp_line
			(start -0.12065 -0.2794)
			(end 0.12065 -0.2794)
			(stroke
				(width 0.1)
				(type default)
			)
			(layer "F.Fab")
		)
		(fp_line
			(start -0.12065 0.2794)
			(end -0.12065 0.3048)
			(stroke
				(width 0.1)
				(type default)
			)
			(layer "F.Fab")
		)
		(fp_line
			(start -0.12065 0.3048)
			(end -0.67945 0.3048)
			(stroke
				(width 0.1)
				(type default)
			)
			(layer "F.Fab")
		)
		(fp_line
			(start 0.120396 0.2794)
			(end -0.12065 0.2794)
			(stroke
				(width 0.1)
				(type default)
			)
			(layer "F.Fab")
		)
		(fp_line
			(start 0.120396 0.3048)
			(end 0.120396 0.2794)
			(stroke
				(width 0.1)
				(type default)
			)
			(layer "F.Fab")
		)
		(fp_line
			(start 0.12065 -0.3048)
			(end 0.67945 -0.3048)
			(stroke
				(width 0.1)
				(type default)
			)
			(layer "F.Fab")
		)
		(fp_line
			(start 0.12065 -0.2794)
			(end 0.12065 -0.3048)
			(stroke
				(width 0.1)
				(type default)
			)
			(layer "F.Fab")
		)
		(fp_line
			(start 0.67945 -0.3048)
			(end 0.67945 0.3048)
			(stroke
				(width 0.1)
				(type default)
			)
			(layer "F.Fab")
		)
		(fp_line
			(start 0.67945 0.3048)
			(end 0.120396 0.3048)
			(stroke
				(width 0.1)
				(type default)
			)
			(layer "F.Fab")
		)
		(pad "1" smd circle
			(at -0.40005 0)
			(size 0 0)
			(layers "F.Cu" "F.Mask" "F.Paste")
			(net "FM_COMP_P3V3_STBY_CEXT")
		)
		(pad "2" smd circle
			(at 0.40005 0)
			(size 0 0)
			(layers "F.Cu" "F.Mask" "F.Paste")
			(net "GND")
		)
	)
	(footprint ""
		(layer "F.Cu")
		(at 125.65888 -99.405948)
		(property "Reference" "R4398"
			(at 0 0 0)
			(layer "F.SilkS")
			(hide yes)
			(effects
				(font
					(size 1.27 1.27)
				)
			)
		)
		(property "Value" ""
			(at 0 0 0)
			(layer "F.Fab")
			(effects
				(font
					(size 1.27 1.27)
				)
			)
		)
		(duplicate_pad_numbers_are_jumpers no)
		(fp_line
			(start -0.7874 -0.4064)
			(end 0.7874 -0.4064)
			(stroke
				(width 0.1524)
				(type default)
			)
			(layer "F.SilkS")
		)
		(fp_line
			(start -0.7874 0.4064)
			(end -0.7874 -0.4064)
			(stroke
				(width 0.1524)
				(type default)
			)
			(layer "F.SilkS")
		)
		(fp_line
			(start 0.7874 -0.4064)
			(end 0.7874 0.4064)
			(stroke
				(width 0.1524)
				(type default)
			)
			(layer "F.SilkS")
		)
		(fp_line
			(start 0.7874 0.4064)
			(end -0.7874 0.4064)
			(stroke
				(width 0.1524)
				(type default)
			)
			(layer "F.SilkS")
		)
		(fp_line
			(start -0.67945 -0.305054)
			(end -0.12065 -0.305054)
			(stroke
				(width 0.1)
				(type default)
			)
			(layer "F.Fab")
		)
		(fp_line
			(start -0.67945 0.3048)
			(end -0.67945 -0.305054)
			(stroke
				(width 0.1)
				(type default)
			)
			(layer "F.Fab")
		)
		(fp_line
			(start -0.12065 -0.305054)
			(end -0.12065 -0.2794)
			(stroke
				(width 0.1)
				(type default)
			)
			(layer "F.Fab")
		)
		(fp_line
			(start -0.12065 -0.2794)
			(end 0.12065 -0.2794)
			(stroke
				(width 0.1)
				(type default)
			)
			(layer "F.Fab")
		)
		(fp_line
			(start -0.12065 0.2794)
			(end -0.12065 0.3048)
			(stroke
				(width 0.1)
				(type default)
			)
			(layer "F.Fab")
		)
		(fp_line
			(start -0.12065 0.3048)
			(end -0.67945 0.3048)
			(stroke
				(width 0.1)
				(type default)
			)
			(layer "F.Fab")
		)
		(fp_line
			(start 0.120396 0.2794)
			(end -0.12065 0.2794)
			(stroke
				(width 0.1)
				(type default)
			)
			(layer "F.Fab")
		)
		(fp_line
			(start 0.120396 0.3048)
			(end 0.120396 0.2794)
			(stroke
				(width 0.1)
				(type default)
			)
			(layer "F.Fab")
		)
		(fp_line
			(start 0.12065 -0.3048)
			(end 0.67945 -0.3048)
			(stroke
				(width 0.1)
				(type default)
			)
			(layer "F.Fab")
		)
		(fp_line
			(start 0.12065 -0.2794)
			(end 0.12065 -0.3048)
			(stroke
				(width 0.1)
				(type default)
			)
			(layer "F.Fab")
		)
		(fp_line
			(start 0.67945 -0.3048)
			(end 0.67945 0.3048)
			(stroke
				(width 0.1)
				(type default)
			)
			(layer "F.Fab")
		)
		(fp_line
			(start 0.67945 0.3048)
			(end 0.120396 0.3048)
			(stroke
				(width 0.1)
				(type default)
			)
			(layer "F.Fab")
		)
		(pad "1" smd circle
			(at -0.40005 0)
			(size 0 0)
			(layers "F.Cu" "F.Mask" "F.Paste")
			(net "H_CPU1_THERMTRIP_N")
		)
		(pad "2" smd circle
			(at 0.40005 0)
			(size 0 0)
			(layers "F.Cu" "F.Mask" "F.Paste")
			(net "H_CPU1_THERMTRIP_R_N")
		)
	)
	(footprint ""
		(layer "F.Cu")
		(at 451.81774 -115.22456 90)
		(property "Reference" "R4764"
			(at 0 0 90)
			(layer "F.SilkS")
			(hide yes)
			(effects
				(font
					(size 1.27 1.27)
				)
			)
		)
		(property "Value" ""
			(at 0 0 90)
			(layer "F.Fab")
			(effects
				(font
					(size 1.27 1.27)
				)
			)
		)
		(duplicate_pad_numbers_are_jumpers no)
		(fp_line
			(start 0.7874 -0.4064)
			(end 0.7874 0.4064)
			(stroke
				(width 0.1524)
				(type default)
			)
			(layer "F.SilkS")
		)
		(fp_line
			(start -0.7874 -0.4064)
			(end 0.7874 -0.4064)
			(stroke
				(width 0.1524)
				(type default)
			)
			(layer "F.SilkS")
		)
		(fp_line
			(start 0.7874 0.4064)
			(end -0.7874 0.4064)
			(stroke
				(width 0.1524)
				(type default)
			)
			(layer "F.SilkS")
		)
		(fp_line
			(start -0.7874 0.4064)
			(end -0.7874 -0.4064)
			(stroke
				(width 0.1524)
				(type default)
			)
			(layer "F.SilkS")
		)
		(fp_line
			(start -0.12065 -0.305054)
			(end -0.12065 -0.2794)
			(stroke
				(width 0.1)
				(type default)
			)
			(layer "F.Fab")
		)
		(fp_line
			(start -0.67945 -0.305054)
			(end -0.12065 -0.305054)
			(stroke
				(width 0.1)
				(type default)
			)
			(layer "F.Fab")
		)
		(fp_line
			(start 0.67945 -0.3048)
			(end 0.67945 0.3048)
			(stroke
				(width 0.1)
				(type default)
			)
			(layer "F.Fab")
		)
		(fp_line
			(start 0.12065 -0.3048)
			(end 0.67945 -0.3048)
			(stroke
				(width 0.1)
				(type default)
			)
			(layer "F.Fab")
		)
		(fp_line
			(start 0.12065 -0.2794)
			(end 0.12065 -0.3048)
			(stroke
				(width 0.1)
				(type default)
			)
			(layer "F.Fab")
		)
		(fp_line
			(start -0.12065 -0.2794)
			(end 0.12065 -0.2794)
			(stroke
				(width 0.1)
				(type default)
			)
			(layer "F.Fab")
		)
		(fp_line
			(start 0.120396 0.2794)
			(end -0.12065 0.2794)
			(stroke
				(width 0.1)
				(type default)
			)
			(layer "F.Fab")
		)
		(fp_line
			(start -0.12065 0.2794)
			(end -0.12065 0.3048)
			(stroke
				(width 0.1)
				(type default)
			)
			(layer "F.Fab")
		)
		(fp_line
			(start 0.67945 0.3048)
			(end 0.120396 0.3048)
			(stroke
				(width 0.1)
				(type default)
			)
			(layer "F.Fab")
		)
		(fp_line
			(start 0.120396 0.3048)
			(end 0.120396 0.2794)
			(stroke
				(width 0.1)
				(type default)
			)
			(layer "F.Fab")
		)
		(fp_line
			(start -0.12065 0.3048)
			(end -0.67945 0.3048)
			(stroke
				(width 0.1)
				(type default)
			)
			(layer "F.Fab")
		)
		(fp_line
			(start -0.67945 0.3048)
			(end -0.67945 -0.305054)
			(stroke
				(width 0.1)
				(type default)
			)
			(layer "F.Fab")
		)
		(pad "1" smd circle
			(at -0.40005 0 90)
			(size 0 0)
			(layers "F.Cu" "F.Mask" "F.Paste")
			(net "P3V3_AUX")
		)
		(pad "2" smd circle
			(at 0.40005 0 90)
			(size 0 0)
			(layers "F.Cu" "F.Mask" "F.Paste")
			(net "HP_OCP_V3_1_EN")
		)
	)
	(footprint ""
		(layer "F.Cu")
		(at 29.869638 -125.194314 -90)
		(property "Reference" "PC477"
			(at 0 0 270)
			(layer "F.SilkS")
			(hide yes)
			(effects
				(font
					(size 1.27 1.27)
				)
			)
		)
		(property "Value" ""
			(at 0 0 270)
			(layer "F.Fab")
			(effects
				(font
					(size 1.27 1.27)
				)
			)
		)
		(duplicate_pad_numbers_are_jumpers no)
		(fp_line
			(start -0.7874 0.4064)
			(end -0.7874 -0.4064)
			(stroke
				(width 0.1524)
				(type default)
			)
			(layer "F.SilkS")
		)
		(fp_line
			(start 0.7874 0.4064)
			(end -0.7874 0.4064)
			(stroke
				(width 0.1524)
				(type default)
			)
			(layer "F.SilkS")
		)
		(fp_line
			(start -0.7874 -0.4064)
			(end 0.7874 -0.4064)
			(stroke
				(width 0.1524)
				(type default)
			)
			(layer "F.SilkS")
		)
		(fp_line
			(start 0.7874 -0.4064)
			(end 0.7874 0.4064)
			(stroke
				(width 0.1524)
				(type default)
			)
			(layer "F.SilkS")
		)
		(fp_line
			(start -0.67945 0.3048)
			(end -0.67945 -0.305054)
			(stroke
				(width 0.1)
				(type default)
			)
			(layer "F.Fab")
		)
		(fp_line
			(start -0.12065 0.3048)
			(end -0.67945 0.3048)
			(stroke
				(width 0.1)
				(type default)
			)
			(layer "F.Fab")
		)
		(fp_line
			(start 0.120396 0.3048)
			(end 0.120396 0.2794)
			(stroke
				(width 0.1)
				(type default)
			)
			(layer "F.Fab")
		)
		(fp_line
			(start 0.67945 0.3048)
			(end 0.120396 0.3048)
			(stroke
				(width 0.1)
				(type default)
			)
			(layer "F.Fab")
		)
		(fp_line
			(start -0.12065 0.2794)
			(end -0.12065 0.3048)
			(stroke
				(width 0.1)
				(type default)
			)
			(layer "F.Fab")
		)
		(fp_line
			(start 0.120396 0.2794)
			(end -0.12065 0.2794)
			(stroke
				(width 0.1)
				(type default)
			)
			(layer "F.Fab")
		)
		(fp_line
			(start -0.12065 -0.2794)
			(end 0.12065 -0.2794)
			(stroke
				(width 0.1)
				(type default)
			)
			(layer "F.Fab")
		)
		(fp_line
			(start 0.12065 -0.2794)
			(end 0.12065 -0.3048)
			(stroke
				(width 0.1)
				(type default)
			)
			(layer "F.Fab")
		)
		(fp_line
			(start 0.12065 -0.3048)
			(end 0.67945 -0.3048)
			(stroke
				(width 0.1)
				(type default)
			)
			(layer "F.Fab")
		)
		(fp_line
			(start 0.67945 -0.3048)
			(end 0.67945 0.3048)
			(stroke
				(width 0.1)
				(type default)
			)
			(layer "F.Fab")
		)
		(fp_line
			(start -0.67945 -0.305054)
			(end -0.12065 -0.305054)
			(stroke
				(width 0.1)
				(type default)
			)
			(layer "F.Fab")
		)
		(fp_line
			(start -0.12065 -0.305054)
			(end -0.12065 -0.2794)
			(stroke
				(width 0.1)
				(type default)
			)
			(layer "F.Fab")
		)
		(pad "1" smd circle
			(at -0.40005 0 270)
			(size 0 0)
			(layers "F.Cu" "F.Mask" "F.Paste")
			(net "PVCCINFAON_CPU1_VREF")
		)
		(pad "2" smd circle
			(at 0.40005 0 270)
			(size 0 0)
			(layers "F.Cu" "F.Mask" "F.Paste")
			(net "GND")
		)
	)
	(footprint ""
		(layer "F.Cu")
		(at 355.219 -393.283948 180)
		(property "Reference" "R4571"
			(at 0 0 180)
			(layer "F.SilkS")
			(hide yes)
			(effects
				(font
					(size 1.27 1.27)
				)
			)
		)
		(property "Value" ""
			(at 0 0 180)
			(layer "F.Fab")
			(effects
				(font
					(size 1.27 1.27)
				)
			)
		)
		(duplicate_pad_numbers_are_jumpers no)
		(fp_line
			(start 0.7874 0.4064)
			(end -0.7874 0.4064)
			(stroke
				(width 0.1524)
				(type default)
			)
			(layer "F.SilkS")
		)
		(fp_line
			(start 0.7874 -0.4064)
			(end 0.7874 0.4064)
			(stroke
				(width 0.1524)
				(type default)
			)
			(layer "F.SilkS")
		)
		(fp_line
			(start -0.7874 0.4064)
			(end -0.7874 -0.4064)
			(stroke
				(width 0.1524)
				(type default)
			)
			(layer "F.SilkS")
		)
		(fp_line
			(start -0.7874 -0.4064)
			(end 0.7874 -0.4064)
			(stroke
				(width 0.1524)
				(type default)
			)
			(layer "F.SilkS")
		)
		(fp_line
			(start 0.67945 0.3048)
			(end 0.120396 0.3048)
			(stroke
				(width 0.1)
				(type default)
			)
			(layer "F.Fab")
		)
		(fp_line
			(start 0.67945 -0.3048)
			(end 0.67945 0.3048)
			(stroke
				(width 0.1)
				(type default)
			)
			(layer "F.Fab")
		)
		(fp_line
			(start 0.12065 -0.2794)
			(end 0.12065 -0.3048)
			(stroke
				(width 0.1)
				(type default)
			)
			(layer "F.Fab")
		)
		(fp_line
			(start 0.12065 -0.3048)
			(end 0.67945 -0.3048)
			(stroke
				(width 0.1)
				(type default)
			)
			(layer "F.Fab")
		)
		(fp_line
			(start 0.120396 0.3048)
			(end 0.120396 0.2794)
			(stroke
				(width 0.1)
				(type default)
			)
			(layer "F.Fab")
		)
		(fp_line
			(start 0.120396 0.2794)
			(end -0.12065 0.2794)
			(stroke
				(width 0.1)
				(type default)
			)
			(layer "F.Fab")
		)
		(fp_line
			(start -0.12065 0.3048)
			(end -0.67945 0.3048)
			(stroke
				(width 0.1)
				(type default)
			)
			(layer "F.Fab")
		)
		(fp_line
			(start -0.12065 0.2794)
			(end -0.12065 0.3048)
			(stroke
				(width 0.1)
				(type default)
			)
			(layer "F.Fab")
		)
		(fp_line
			(start -0.12065 -0.2794)
			(end 0.12065 -0.2794)
			(stroke
				(width 0.1)
				(type default)
			)
			(layer "F.Fab")
		)
		(fp_line
			(start -0.12065 -0.305054)
			(end -0.12065 -0.2794)
			(stroke
				(width 0.1)
				(type default)
			)
			(layer "F.Fab")
		)
		(fp_line
			(start -0.67945 0.3048)
			(end -0.67945 -0.305054)
			(stroke
				(width 0.1)
				(type default)
			)
			(layer "F.Fab")
		)
		(fp_line
			(start -0.67945 -0.305054)
			(end -0.12065 -0.305054)
			(stroke
				(width 0.1)
				(type default)
			)
			(layer "F.Fab")
		)
		(pad "1" smd circle
			(at -0.40005 0 180)
			(size 0 0)
			(layers "F.Cu" "F.Mask" "F.Paste")
			(net "GPU_3V3IO_RSVD4")
		)
		(pad "2" smd circle
			(at 0.40005 0 180)
			(size 0 0)
			(layers "F.Cu" "F.Mask" "F.Paste")
			(net "GPU_3V3IO_RSVD4_ISO")
		)
	)
	(footprint ""
		(layer "F.Cu")
		(at 86.741 -41.112948)
		(property "Reference" "R4617"
			(at 0 0 0)
			(layer "F.SilkS")
			(hide yes)
			(effects
				(font
					(size 1.27 1.27)
				)
			)
		)
		(property "Value" ""
			(at 0 0 0)
			(layer "F.Fab")
			(effects
				(font
					(size 1.27 1.27)
				)
			)
		)
		(duplicate_pad_numbers_are_jumpers no)
		(fp_line
			(start -0.7874 -0.4064)
			(end 0.7874 -0.4064)
			(stroke
				(width 0.1524)
				(type default)
			)
			(layer "F.SilkS")
		)
		(fp_line
			(start -0.7874 0.4064)
			(end -0.7874 -0.4064)
			(stroke
				(width 0.1524)
				(type default)
			)
			(layer "F.SilkS")
		)
		(fp_line
			(start 0.7874 -0.4064)
			(end 0.7874 0.4064)
			(stroke
				(width 0.1524)
				(type default)
			)
			(layer "F.SilkS")
		)
		(fp_line
			(start 0.7874 0.4064)
			(end -0.7874 0.4064)
			(stroke
				(width 0.1524)
				(type default)
			)
			(layer "F.SilkS")
		)
		(fp_line
			(start -0.67945 -0.305054)
			(end -0.12065 -0.305054)
			(stroke
				(width 0.1)
				(type default)
			)
			(layer "F.Fab")
		)
		(fp_line
			(start -0.67945 0.3048)
			(end -0.67945 -0.305054)
			(stroke
				(width 0.1)
				(type default)
			)
			(layer "F.Fab")
		)
		(fp_line
			(start -0.12065 -0.305054)
			(end -0.12065 -0.2794)
			(stroke
				(width 0.1)
				(type default)
			)
			(layer "F.Fab")
		)
		(fp_line
			(start -0.12065 -0.2794)
			(end 0.12065 -0.2794)
			(stroke
				(width 0.1)
				(type default)
			)
			(layer "F.Fab")
		)
		(fp_line
			(start -0.12065 0.2794)
			(end -0.12065 0.3048)
			(stroke
				(width 0.1)
				(type default)
			)
			(layer "F.Fab")
		)
		(fp_line
			(start -0.12065 0.3048)
			(end -0.67945 0.3048)
			(stroke
				(width 0.1)
				(type default)
			)
			(layer "F.Fab")
		)
		(fp_line
			(start 0.120396 0.2794)
			(end -0.12065 0.2794)
			(stroke
				(width 0.1)
				(type default)
			)
			(layer "F.Fab")
		)
		(fp_line
			(start 0.120396 0.3048)
			(end 0.120396 0.2794)
			(stroke
				(width 0.1)
				(type default)
			)
			(layer "F.Fab")
		)
		(fp_line
			(start 0.12065 -0.3048)
			(end 0.67945 -0.3048)
			(stroke
				(width 0.1)
				(type default)
			)
			(layer "F.Fab")
		)
		(fp_line
			(start 0.12065 -0.2794)
			(end 0.12065 -0.3048)
			(stroke
				(width 0.1)
				(type default)
			)
			(layer "F.Fab")
		)
		(fp_line
			(start 0.67945 -0.3048)
			(end 0.67945 0.3048)
			(stroke
				(width 0.1)
				(type default)
			)
			(layer "F.Fab")
		)
		(fp_line
			(start 0.67945 0.3048)
			(end 0.120396 0.3048)
			(stroke
				(width 0.1)
				(type default)
			)
			(layer "F.Fab")
		)
		(pad "1" smd circle
			(at -0.40005 0)
			(size 0 0)
			(layers "F.Cu" "F.Mask" "F.Paste")
			(net "HP_LVC3_OCP_V3_2_PWRGD")
		)
		(pad "2" smd circle
			(at 0.40005 0)
			(size 0 0)
			(layers "F.Cu" "F.Mask" "F.Paste")
			(net "HP_LVC3_OCP_V3_2_PWRGD_R")
		)
	)
)
